# S9S_MB_2U (Grand Teton) — schematic netlist excerpt (pin names and nets, part order shuffled) for the footprints in the layout excerpt that follows; sources: Cadence DE-HDL packaged netlist, KiCad conversion of 03242023_DA0F0TMBIJ0_F0T_Motherboard_J_brd_V01_OCP.brd

R4593  Q_RES  0 5% CHIP  pkg 0402LF  page 266 : A = IRQ_PVCCIN_CPU0_VRHOT_R_N ; B = IRQ_PVCCIN_CPU0_VRHOT_N
PC1178  Q_CAP  100NF 50V 10% X7R  pkg C0402  page 272 : A = SW_PVCCFA_EHV_FIVRA_CPU0_BOOT4_ ; B = SW_PVCCFA_EHV_FIVRA_CPU0_BOOTR4

(kicad_pcb
	(version 20260206)
	(generator "pcbnew")
	(generator_version "10.0")
	(general
		(thickness 1.6)
		(legacy_teardrops no)
	)
	(paper "A4")
	(title_block
		(title "03242023_DA0F0TMBIJ0_F0T_Motherboard_J_brd_V01_OCP.brd")
		(comment 1 "Grand Teton / footprints 1248-1249 of 6105")
	)
	(layers
		(0 "F.Cu" signal "TOP")
		(4 "In1.Cu" signal "GND")
		(6 "In2.Cu" signal "IN1")
		(8 "In3.Cu" signal "GND1")
		(10 "In4.Cu" signal "IN2")
		(12 "In5.Cu" signal "GND2")
		(14 "In6.Cu" signal "IN3")
		(16 "In7.Cu" signal "GND3")
		(18 "In8.Cu" signal "VCC")
		(20 "In9.Cu" signal "VCC1")
		(22 "In10.Cu" signal "GND4")
		(24 "In11.Cu" signal "IN4")
		(26 "In12.Cu" signal "GND5")
		(28 "In13.Cu" signal "IN5")
		(30 "In14.Cu" signal "GND6")
		(32 "In15.Cu" signal "IN6")
		(34 "In16.Cu" signal "GND7")
		(2 "B.Cu" signal "BOTTOM")
		(9 "F.Adhes" user "F.Adhesive")
		(11 "B.Adhes" user "B.Adhesive")
		(13 "F.Paste" user "Package Geometry/Pastemask Top")
		(15 "B.Paste" user "Package Geometry/Pastemask Bottom")
		(5 "F.SilkS" user "Ref Des/Silkscreen Top")
		(7 "B.SilkS" user "Ref Des/Silkscreen Bottom")
		(1 "F.Mask" user "Board Geometry/Soldermask Top")
		(3 "B.Mask" user "Board Geometry/Soldermask Bottom")
		(17 "Dwgs.User" user "User.Drawings")
		(19 "Cmts.User" user "User.Comments")
		(21 "Eco1.User" user "User.Eco1")
		(23 "Eco2.User" user "User.Eco2")
		(25 "Edge.Cuts" user "Board Geometry/Outline")
		(27 "Margin" user)
		(31 "F.CrtYd" user "Package Geometry/Place Bound Top")
		(29 "B.CrtYd" user "Package Geometry/Place Bound Bottom")
		(35 "F.Fab" user "Ref Des/Assembly Top")
		(33 "B.Fab" user "Ref Des/Assembly Bottom")
	)
	(footprint ""
		(layer "F.Cu")
		(at 290.571936 -367.378996 -90)
		(property "Reference" "PC1178"
			(at 0 0 270)
			(layer "F.SilkS")
			(hide yes)
			(effects
				(font
					(size 1.27 1.27)
				)
			)
		)
		(property "Value" ""
			(at 0 0 270)
			(layer "F.Fab")
			(effects
				(font
					(size 1.27 1.27)
				)
			)
		)
		(duplicate_pad_numbers_are_jumpers no)
		(fp_line
			(start -0.7874 0.4064)
			(end -0.7874 -0.4064)
			(stroke
				(width 0.1524)
				(type default)
			)
			(layer "F.SilkS")
		)
		(fp_line
			(start 0.7874 0.4064)
			(end -0.7874 0.4064)
			(stroke
				(width 0.1524)
				(type default)
			)
			(layer "F.SilkS")
		)
		(fp_line
			(start -0.7874 -0.4064)
			(end 0.7874 -0.4064)
			(stroke
				(width 0.1524)
				(type default)
			)
			(layer "F.SilkS")
		)
		(fp_line
			(start 0.7874 -0.4064)
			(end 0.7874 0.4064)
			(stroke
				(width 0.1524)
				(type default)
			)
			(layer "F.SilkS")
		)
		(fp_line
			(start -0.67945 0.3048)
			(end -0.67945 -0.305054)
			(stroke
				(width 0.1)
				(type default)
			)
			(layer "F.Fab")
		)
		(fp_line
			(start -0.12065 0.3048)
			(end -0.67945 0.3048)
			(stroke
				(width 0.1)
				(type default)
			)
			(layer "F.Fab")
		)
		(fp_line
			(start 0.120396 0.3048)
			(end 0.120396 0.2794)
			(stroke
				(width 0.1)
				(type default)
			)
			(layer "F.Fab")
		)
		(fp_line
			(start 0.67945 0.3048)
			(end 0.120396 0.3048)
			(stroke
				(width 0.1)
				(type default)
			)
			(layer "F.Fab")
		)
		(fp_line
			(start -0.12065 0.2794)
			(end -0.12065 0.3048)
			(stroke
				(width 0.1)
				(type default)
			)
			(layer "F.Fab")
		)
		(fp_line
			(start 0.120396 0.2794)
			(end -0.12065 0.2794)
			(stroke
				(width 0.1)
				(type default)
			)
			(layer "F.Fab")
		)
		(fp_line
			(start -0.12065 -0.2794)
			(end 0.12065 -0.2794)
			(stroke
				(width 0.1)
				(type default)
			)
			(layer "F.Fab")
		)
		(fp_line
			(start 0.12065 -0.2794)
			(end 0.12065 -0.3048)
			(stroke
				(width 0.1)
				(type default)
			)
			(layer "F.Fab")
		)
		(fp_line
			(start 0.12065 -0.3048)
			(end 0.67945 -0.3048)
			(stroke
				(width 0.1)
				(type default)
			)
			(layer "F.Fab")
		)
		(fp_line
			(start 0.67945 -0.3048)
			(end 0.67945 0.3048)
			(stroke
				(width 0.1)
				(type default)
			)
			(layer "F.Fab")
		)
		(fp_line
			(start -0.67945 -0.305054)
			(end -0.12065 -0.305054)
			(stroke
				(width 0.1)
				(type default)
			)
			(layer "F.Fab")
		)
		(fp_line
			(start -0.12065 -0.305054)
			(end -0.12065 -0.2794)
			(stroke
				(width 0.1)
				(type default)
			)
			(layer "F.Fab")
		)
		(pad "1" smd circle
			(at -0.40005 0 270)
			(size 0 0)
			(layers "F.Cu" "F.Mask" "F.Paste")
			(net "SW_PVCCFA_EHV_FIVRA_CPU0_BOOT4_")
		)
		(pad "2" smd circle
			(at 0.40005 0 270)
			(size 0 0)
			(layers "F.Cu" "F.Mask" "F.Paste")
			(net "SW_PVCCFA_EHV_FIVRA_CPU0_BOOTR4")
		)
	)
	(footprint ""
		(layer "F.Cu")
		(at 351.189798 -359.53573 180)
		(property "Reference" "R4593"
			(at 0 0 180)
			(layer "F.SilkS")
			(hide yes)
			(effects
				(font
					(size 1.27 1.27)
				)
			)
		)
		(property "Value" ""
			(at 0 0 180)
			(layer "F.Fab")
			(effects
				(font
					(size 1.27 1.27)
				)
			)
		)
		(duplicate_pad_numbers_are_jumpers no)
		(fp_line
			(start 0.7874 0.4064)
			(end -0.7874 0.4064)
			(stroke
				(width 0.1524)
				(type default)
			)
			(layer "F.SilkS")
		)
		(fp_line
			(start 0.7874 -0.4064)
			(end 0.7874 0.4064)
			(stroke
				(width 0.1524)
				(type default)
			)
			(layer "F.SilkS")
		)
		(fp_line
			(start -0.7874 0.4064)
			(end -0.7874 -0.4064)
			(stroke
				(width 0.1524)
				(type default)
			)
			(layer "F.SilkS")
		)
		(fp_line
			(start -0.7874 -0.4064)
			(end 0.7874 -0.4064)
			(stroke
				(width 0.1524)
				(type default)
			)
			(layer "F.SilkS")
		)
		(fp_line
			(start 0.67945 0.3048)
			(end 0.120396 0.3048)
			(stroke
				(width 0.1)
				(type default)
			)
			(layer "F.Fab")
		)
		(fp_line
			(start 0.67945 -0.3048)
			(end 0.67945 0.3048)
			(stroke
				(width 0.1)
				(type default)
			)
			(layer "F.Fab")
		)
		(fp_line
			(start 0.12065 -0.2794)
			(end 0.12065 -0.3048)
			(stroke
				(width 0.1)
				(type default)
			)
			(layer "F.Fab")
		)
		(fp_line
			(start 0.12065 -0.3048)
			(end 0.67945 -0.3048)
			(stroke
				(width 0.1)
				(type default)
			)
			(layer "F.Fab")
		)
		(fp_line
			(start 0.120396 0.3048)
			(end 0.120396 0.2794)
			(stroke
				(width 0.1)
				(type default)
			)
			(layer "F.Fab")
		)
		(fp_line
			(start 0.120396 0.2794)
			(end -0.12065 0.2794)
			(stroke
				(width 0.1)
				(type default)
			)
			(layer "F.Fab")
		)
		(fp_line
			(start -0.12065 0.3048)
			(end -0.67945 0.3048)
			(stroke
				(width 0.1)
				(type default)
			)
			(layer "F.Fab")
		)
		(fp_line
			(start -0.12065 0.2794)
			(end -0.12065 0.3048)
			(stroke
				(width 0.1)
				(type default)
			)
			(layer "F.Fab")
		)
		(fp_line
			(start -0.12065 -0.2794)
			(end 0.12065 -0.2794)
			(stroke
				(width 0.1)
				(type default)
			)
			(layer "F.Fab")
		)
		(fp_line
			(start -0.12065 -0.305054)
			(end -0.12065 -0.2794)
			(stroke
				(width 0.1)
				(type default)
			)
			(layer "F.Fab")
		)
		(fp_line
			(start -0.67945 0.3048)
			(end -0.67945 -0.305054)
			(stroke
				(width 0.1)
				(type default)
			)
			(layer "F.Fab")
		)
		(fp_line
			(start -0.67945 -0.305054)
			(end -0.12065 -0.305054)
			(stroke
				(width 0.1)
				(type default)
			)
			(layer "F.Fab")
		)
		(pad "1" smd circle
			(at -0.40005 0 180)
			(size 0 0)
			(layers "F.Cu" "F.Mask" "F.Paste")
			(net "IRQ_PVCCIN_CPU0_VRHOT_R_N")
		)
		(pad "2" smd circle
			(at 0.40005 0 180)
			(size 0 0)
			(layers "F.Cu" "F.Mask" "F.Paste")
			(net "IRQ_PVCCIN_CPU0_VRHOT_N")
		)
	)
)
